(kicad_pcb
	(version 20260206)
	(generator "pcbnew")
	(generator_version "10.0")
	(general
		(thickness 1.6)
		(legacy_teardrops no)
	)
	(paper "A4")
	(title_block
		(title "Bryce Canyon_R.DPB_16317-1_OCP.brd")
		(comment 1 "Bryce Canyon / footprints 1065-1072 of 2099")
	)
	(layers
		(0 "F.Cu" signal "TOP")
		(4 "In1.Cu" signal "L2GND")
		(6 "In2.Cu" signal "L3")
		(8 "In3.Cu" signal "L4VCC")
		(10 "In4.Cu" signal "L5VCC")
		(12 "In5.Cu" signal "L6")
		(14 "In6.Cu" signal "L7GND")
		(2 "B.Cu" signal "BOTTOM")
		(9 "F.Adhes" user "F.Adhesive")
		(11 "B.Adhes" user "B.Adhesive")
		(13 "F.Paste" user "Package Geometry/Pastemask Top")
		(15 "B.Paste" user "Package Geometry/Pastemask Bottom")
		(5 "F.SilkS" user "Ref Des/Silkscreen Top")
		(7 "B.SilkS" user "Ref Des/Silkscreen Bottom")
		(1 "F.Mask" user "Board Geometry/Soldermask Top")
		(3 "B.Mask" user "Board Geometry/Soldermask Bottom")
		(17 "Dwgs.User" user "User.Drawings")
		(19 "Cmts.User" user "User.Comments")
		(21 "Eco1.User" user "User.Eco1")
		(23 "Eco2.User" user "User.Eco2")
		(25 "Edge.Cuts" user "Board Geometry/Outline")
		(27 "Margin" user)
		(31 "F.CrtYd" user "Package Geometry/Place Bound Top")
		(29 "B.CrtYd" user "Package Geometry/Place Bound Bottom")
		(35 "F.Fab" user "Ref Des/Assembly Top")
		(33 "B.Fab" user "Ref Des/Assembly Bottom")
	)
	(footprint ""
		(layer "F.Cu")
		(at 20.066 -146.939 -90)
		(property "Reference" "C187"
			(at 0 0 270)
			(layer "F.SilkS")
			(hide yes)
			(effects
				(font
					(size 1.27 1.27)
				)
			)
		)
		(property "Value" "SC10U16V6KX-2GP"
			(at -0.0762 -5.1308 270)
			(unlocked yes)
			(layer "F.Fab")
			(hide yes)
			(effects
				(font
					(size 1.016 1.016)
					(thickness 0.1524)
				)
			)
		)
		(property "Device Type" "C1206H71"
			(at -0.127 -6.6548 270)
			(unlocked yes)
			(layer "F.Fab")
			(hide yes)
			(effects
				(font
					(size 1.016 1.016)
					(thickness 0.1524)
				)
			)
		)
		(duplicate_pad_numbers_are_jumpers no)
		(fp_line
			(start -1.016 2.2352)
			(end -1.016 0.8382)
			(stroke
				(width 0.1524)
				(type default)
			)
			(layer "F.SilkS")
		)
		(fp_line
			(start 1.016 2.2352)
			(end -1.016 2.2352)
			(stroke
				(width 0.1524)
				(type default)
			)
			(layer "F.SilkS")
		)
		(fp_line
			(start 1.016 0.8382)
			(end 1.016 2.2352)
			(stroke
				(width 0.1524)
				(type default)
			)
			(layer "F.SilkS")
		)
		(fp_line
			(start -1.016 -0.8382)
			(end -1.016 -2.2352)
			(stroke
				(width 0.1524)
				(type default)
			)
			(layer "F.SilkS")
		)
		(fp_line
			(start -1.016 -2.2352)
			(end 1.016 -2.2352)
			(stroke
				(width 0.1524)
				(type default)
			)
			(layer "F.SilkS")
		)
		(fp_line
			(start 1.016 -2.2352)
			(end 1.016 -0.8382)
			(stroke
				(width 0.1524)
				(type default)
			)
			(layer "F.SilkS")
		)
		(fp_rect
			(start -1.0922 2.3114)
			(end 1.0922 -2.3114)
			(stroke
				(width 0)
				(type default)
			)
			(fill no)
			(layer "F.CrtYd")
		)
		(fp_poly
			(pts
				(xy 1.0922 -2.3114) (xy 1.0922 2.3114) (xy -1.0922 2.3114) (xy -1.0922 -2.3114)
			)
			(stroke
				(width 0)
				(type default)
			)
			(fill no)
			(layer "F.Fab")
		)
		(pad "1" smd rect
			(at 0 -1.397 270)
			(size 1.651 1.27)
			(layers "F.Cu" "F.Mask" "F.Paste")
			(net "P5V_HDD12")
		)
		(pad "2" smd rect
			(at 0 1.397 270)
			(size 1.651 1.27)
			(layers "F.Cu" "F.Mask" "F.Paste")
			(net "GND")
		)
	)
	(footprint ""
		(layer "F.Cu")
		(at 23.749 -148.209)
		(property "Reference" "R350"
			(at 0 0 0)
			(layer "F.SilkS")
			(hide yes)
			(effects
				(font
					(size 1.27 1.27)
				)
			)
		)
		(property "Value" "2R6F-GP"
			(at -0.0508 -4.8514 0)
			(unlocked yes)
			(layer "F.Fab")
			(hide yes)
			(effects
				(font
					(size 1.016 1.016)
					(thickness 0.1524)
				)
			)
		)
		(property "Device Type" "R1206H26"
			(at 0 -6.3754 0)
			(unlocked yes)
			(layer "F.Fab")
			(hide yes)
			(effects
				(font
					(size 1.016 1.016)
					(thickness 0.1524)
				)
			)
		)
		(duplicate_pad_numbers_are_jumpers no)
		(fp_line
			(start -1.016 -2.2352)
			(end 1.016 -2.2352)
			(stroke
				(width 0.1524)
				(type default)
			)
			(layer "F.SilkS")
		)
		(fp_line
			(start -1.016 2.2352)
			(end -1.016 -2.2352)
			(stroke
				(width 0.1524)
				(type default)
			)
			(layer "F.SilkS")
		)
		(fp_line
			(start 1.016 -2.2352)
			(end 1.016 2.2352)
			(stroke
				(width 0.1524)
				(type default)
			)
			(layer "F.SilkS")
		)
		(fp_line
			(start 1.016 2.2352)
			(end -1.016 2.2352)
			(stroke
				(width 0.1524)
				(type default)
			)
			(layer "F.SilkS")
		)
		(fp_rect
			(start -1.0922 2.3114)
			(end 1.0922 -2.3114)
			(stroke
				(width 0)
				(type default)
			)
			(fill no)
			(layer "F.CrtYd")
		)
		(fp_poly
			(pts
				(xy -1.0922 -2.3114) (xy 1.0922 -2.3114) (xy 1.0922 2.3114) (xy -1.0922 2.3114)
			)
			(stroke
				(width 0)
				(type default)
			)
			(fill no)
			(layer "F.Fab")
		)
		(pad "1" smd rect
			(at 0 -1.397)
			(size 1.651 1.27)
			(layers "F.Cu" "F.Mask" "F.Paste")
			(net "P5V_HDD12")
		)
		(pad "2" smd rect
			(at 0 1.397)
			(size 1.651 1.27)
			(layers "F.Cu" "F.Mask" "F.Paste")
			(net "5V_PRE_12")
		)
	)
	(footprint ""
		(layer "F.Cu")
		(at 232.22204 -233.01198 180)
		(property "Reference" "R70"
			(at 0 0 180)
			(layer "F.SilkS")
			(hide yes)
			(effects
				(font
					(size 1.27 1.27)
				)
			)
		)
		(property "Value" "4K7R2F-GP"
			(at 0.064008 -3.993896 180)
			(unlocked yes)
			(layer "F.Fab")
			(hide yes)
			(effects
				(font
					(size 1.016 1.016)
					(thickness 0.1524)
				)
			)
		)
		(property "Device Type" "R402H16"
			(at 0.064008 -5.517896 180)
			(unlocked yes)
			(layer "F.Fab")
			(hide yes)
			(effects
				(font
					(size 1.016 1.016)
					(thickness 0.1524)
				)
			)
		)
		(duplicate_pad_numbers_are_jumpers no)
		(fp_line
			(start 0.508 -0.9398)
			(end -0.508 -0.9398)
			(stroke
				(width 0.1524)
				(type default)
			)
			(layer "F.SilkS")
		)
		(fp_line
			(start -0.508 -0.9398)
			(end -0.508 0.9398)
			(stroke
				(width 0.1524)
				(type default)
			)
			(layer "F.SilkS")
		)
		(fp_rect
			(start -0.508 0.9398)
			(end 0.508 -0.9398)
			(stroke
				(width 0)
				(type default)
			)
			(fill no)
			(layer "F.CrtYd")
		)
		(fp_rect
			(start -0.508 0.9398)
			(end 0.508 -0.9398)
			(stroke
				(width 0)
				(type default)
			)
			(fill no)
			(layer "F.Fab")
		)
		(pad "1" smd custom
			(at 0 -0.4445 180)
			(size 0.1397 0.1397)
			(layers "F.Cu" "F.Mask" "F.Paste")
			(net "IO_EXP1_A2")
			(options
				(clearance outline)
				(anchor circle)
			)
			(primitives
				(gr_poly
					(pts
						(arc
							(start -0.1778 -0.2794)
							(mid -0.249642 -0.249642)
							(end -0.2794 -0.1778)
						)
						(arc
							(start -0.2794 0.1778)
							(mid -0.249642 0.249642)
							(end -0.1778 0.2794)
						)
						(arc
							(start 0.1778 0.2794)
							(mid 0.249642 0.249642)
							(end 0.2794 0.1778)
						)
						(arc
							(start 0.2794 -0.1778)
							(mid 0.249642 -0.249642)
							(end 0.1778 -0.2794)
						)
					)
					(width 0)
					(fill yes)
				)
			)
		)
		(pad "2" smd custom
			(at 0 0.4445 180)
			(size 0.1397 0.1397)
			(layers "F.Cu" "F.Mask" "F.Paste")
			(net "GND")
			(options
				(clearance outline)
				(anchor circle)
			)
			(primitives
				(gr_poly
					(pts
						(arc
							(start -0.1778 -0.2794)
							(mid -0.249642 -0.249642)
							(end -0.2794 -0.1778)
						)
						(arc
							(start -0.2794 0.1778)
							(mid -0.249642 0.249642)
							(end -0.1778 0.2794)
						)
						(arc
							(start 0.1778 0.2794)
							(mid 0.249642 0.249642)
							(end 0.2794 0.1778)
						)
						(arc
							(start 0.2794 -0.1778)
							(mid 0.249642 -0.249642)
							(end 0.1778 -0.2794)
						)
					)
					(width 0)
					(fill yes)
				)
			)
		)
	)
	(footprint ""
		(layer "F.Cu")
		(at 182.372 -371.602 90)
		(property "Reference" "R987"
			(at 0 0 90)
			(layer "F.SilkS")
			(hide yes)
			(effects
				(font
					(size 1.27 1.27)
				)
			)
		)
		(property "Value" "0R2J-2-GP"
			(at 0.064008 -3.993896 90)
			(unlocked yes)
			(layer "F.Fab")
			(hide yes)
			(effects
				(font
					(size 1.016 1.016)
					(thickness 0.1524)
				)
			)
		)
		(property "Device Type" "R402H16"
			(at 0.064008 -5.517896 90)
			(unlocked yes)
			(layer "F.Fab")
			(hide yes)
			(effects
				(font
					(size 1.016 1.016)
					(thickness 0.1524)
				)
			)
		)
		(duplicate_pad_numbers_are_jumpers no)
		(fp_line
			(start 0.508 -0.9398)
			(end -0.508 -0.9398)
			(stroke
				(width 0.1524)
				(type default)
			)
			(layer "F.SilkS")
		)
		(fp_line
			(start -0.508 -0.9398)
			(end -0.508 0.9398)
			(stroke
				(width 0.1524)
				(type default)
			)
			(layer "F.SilkS")
		)
		(fp_rect
			(start -0.508 0.9398)
			(end 0.508 -0.9398)
			(stroke
				(width 0)
				(type default)
			)
			(fill no)
			(layer "F.CrtYd")
		)
		(fp_rect
			(start -0.508 0.9398)
			(end 0.508 -0.9398)
			(stroke
				(width 0)
				(type default)
			)
			(fill no)
			(layer "F.Fab")
		)
		(pad "1" smd custom
			(at 0 -0.4445 90)
			(size 0.1397 0.1397)
			(layers "F.Cu" "F.Mask" "F.Paste")
			(net "MB0_SCL_R")
			(options
				(clearance outline)
				(anchor circle)
			)
			(primitives
				(gr_poly
					(pts
						(arc
							(start -0.1778 -0.2794)
							(mid -0.249642 -0.249642)
							(end -0.2794 -0.1778)
						)
						(arc
							(start -0.2794 0.1778)
							(mid -0.249642 0.249642)
							(end -0.1778 0.2794)
						)
						(arc
							(start 0.1778 0.2794)
							(mid 0.249642 0.249642)
							(end 0.2794 0.1778)
						)
						(arc
							(start 0.2794 -0.1778)
							(mid 0.249642 -0.249642)
							(end 0.1778 -0.2794)
						)
					)
					(width 0)
					(fill yes)
				)
			)
		)
		(pad "2" smd custom
			(at 0 0.4445 90)
			(size 0.1397 0.1397)
			(layers "F.Cu" "F.Mask" "F.Paste")
			(net "I2C_CLIP_B_SCL")
			(options
				(clearance outline)
				(anchor circle)
			)
			(primitives
				(gr_poly
					(pts
						(arc
							(start -0.1778 -0.2794)
							(mid -0.249642 -0.249642)
							(end -0.2794 -0.1778)
						)
						(arc
							(start -0.2794 0.1778)
							(mid -0.249642 0.249642)
							(end -0.1778 0.2794)
						)
						(arc
							(start 0.1778 0.2794)
							(mid 0.249642 0.249642)
							(end 0.2794 0.1778)
						)
						(arc
							(start 0.2794 -0.1778)
							(mid 0.249642 -0.249642)
							(end 0.1778 -0.2794)
						)
					)
					(width 0)
					(fill yes)
				)
			)
		)
	)
	(footprint ""
		(layer "F.Cu")
		(at 248.778522 -358.876346)
		(property "Reference" "R1042"
			(at 0 0 0)
			(layer "F.SilkS")
			(hide yes)
			(effects
				(font
					(size 1.27 1.27)
				)
			)
		)
		(property "Value" "21KR2F-GP"
			(at 0.064008 -3.993896 0)
			(unlocked yes)
			(layer "F.Fab")
			(hide yes)
			(effects
				(font
					(size 1.016 1.016)
					(thickness 0.1524)
				)
			)
		)
		(property "Device Type" "R402H16"
			(at 0.064008 -5.517896 0)
			(unlocked yes)
			(layer "F.Fab")
			(hide yes)
			(effects
				(font
					(size 1.016 1.016)
					(thickness 0.1524)
				)
			)
		)
		(duplicate_pad_numbers_are_jumpers no)
		(fp_line
			(start -0.508 -0.9398)
			(end -0.508 0.9398)
			(stroke
				(width 0.1524)
				(type default)
			)
			(layer "F.SilkS")
		)
		(fp_line
			(start 0.508 -0.9398)
			(end -0.508 -0.9398)
			(stroke
				(width 0.1524)
				(type default)
			)
			(layer "F.SilkS")
		)
		(fp_rect
			(start -0.508 0.9398)
			(end 0.508 -0.9398)
			(stroke
				(width 0)
				(type default)
			)
			(fill no)
			(layer "F.CrtYd")
		)
		(fp_rect
			(start -0.508 0.9398)
			(end 0.508 -0.9398)
			(stroke
				(width 0)
				(type default)
			)
			(fill no)
			(layer "F.Fab")
		)
		(pad "1" smd custom
			(at 0 -0.4445)
			(size 0.1397 0.1397)
			(layers "F.Cu" "F.Mask" "F.Paste")
			(net "MB3_PSET_R")
			(options
				(clearance outline)
				(anchor circle)
			)
			(primitives
				(gr_poly
					(pts
						(arc
							(start -0.1778 -0.2794)
							(mid -0.249642 -0.249642)
							(end -0.2794 -0.1778)
						)
						(arc
							(start -0.2794 0.1778)
							(mid -0.249642 0.249642)
							(end -0.1778 0.2794)
						)
						(arc
							(start 0.1778 0.2794)
							(mid 0.249642 0.249642)
							(end 0.2794 0.1778)
						)
						(arc
							(start 0.2794 -0.1778)
							(mid 0.249642 -0.249642)
							(end 0.1778 -0.2794)
						)
					)
					(width 0)
					(fill yes)
				)
			)
		)
		(pad "2" smd custom
			(at 0 0.4445)
			(size 0.1397 0.1397)
			(layers "F.Cu" "F.Mask" "F.Paste")
			(net "AGND_CURRENT_DPB")
			(options
				(clearance outline)
				(anchor circle)
			)
			(primitives
				(gr_poly
					(pts
						(arc
							(start -0.1778 -0.2794)
							(mid -0.249642 -0.249642)
							(end -0.2794 -0.1778)
						)
						(arc
							(start -0.2794 0.1778)
							(mid -0.249642 0.249642)
							(end -0.1778 0.2794)
						)
						(arc
							(start 0.1778 0.2794)
							(mid 0.249642 0.249642)
							(end 0.2794 0.1778)
						)
						(arc
							(start 0.2794 -0.1778)
							(mid 0.249642 -0.249642)
							(end 0.1778 -0.2794)
						)
					)
					(width 0)
					(fill yes)
				)
			)
		)
	)
	(footprint ""
		(layer "F.Cu")
		(at 457.581 -147.066 -90)
		(property "Reference" "R575"
			(at 0 0 270)
			(layer "F.SilkS")
			(hide yes)
			(effects
				(font
					(size 1.27 1.27)
				)
			)
		)
		(property "Value" "2R6F-GP"
			(at -0.0508 -4.8514 270)
			(unlocked yes)
			(layer "F.Fab")
			(hide yes)
			(effects
				(font
					(size 1.016 1.016)
					(thickness 0.1524)
				)
			)
		)
		(property "Device Type" "R1206H26"
			(at 0 -6.3754 270)
			(unlocked yes)
			(layer "F.Fab")
			(hide yes)
			(effects
				(font
					(size 1.016 1.016)
					(thickness 0.1524)
				)
			)
		)
		(duplicate_pad_numbers_are_jumpers no)
		(fp_line
			(start -1.016 2.2352)
			(end -1.016 -2.2352)
			(stroke
				(width 0.1524)
				(type default)
			)
			(layer "F.SilkS")
		)
		(fp_line
			(start 1.016 2.2352)
			(end -1.016 2.2352)
			(stroke
				(width 0.1524)
				(type default)
			)
			(layer "F.SilkS")
		)
		(fp_line
			(start -1.016 -2.2352)
			(end 1.016 -2.2352)
			(stroke
				(width 0.1524)
				(type default)
			)
			(layer "F.SilkS")
		)
		(fp_line
			(start 1.016 -2.2352)
			(end 1.016 2.2352)
			(stroke
				(width 0.1524)
				(type default)
			)
			(layer "F.SilkS")
		)
		(fp_rect
			(start -1.0922 2.3114)
			(end 1.0922 -2.3114)
			(stroke
				(width 0)
				(type default)
			)
			(fill no)
			(layer "F.CrtYd")
		)
		(fp_poly
			(pts
				(xy -1.0922 -2.3114) (xy 1.0922 -2.3114) (xy 1.0922 2.3114) (xy -1.0922 2.3114)
			)
			(stroke
				(width 0)
				(type default)
			)
			(fill no)
			(layer "F.Fab")
		)
		(pad "1" smd rect
			(at 0 -1.397 270)
			(size 1.651 1.27)
			(layers "F.Cu" "F.Mask" "F.Paste")
			(net "P5V_HDD22")
		)
		(pad "2" smd rect
			(at 0 1.397 270)
			(size 1.651 1.27)
			(layers "F.Cu" "F.Mask" "F.Paste")
			(net "5V_PRE_22")
		)
	)
	(footprint ""
		(layer "F.Cu")
		(at 118.872 -45.466 180)
		(property "Reference" "C387"
			(at 0 0 180)
			(layer "F.SilkS")
			(hide yes)
			(effects
				(font
					(size 1.27 1.27)
				)
			)
		)
		(property "Value" "SC1U25V3KX-GP"
			(at 0 -2.8194 180)
			(unlocked yes)
			(layer "F.Fab")
			(hide yes)
			(effects
				(font
					(size 1.016 1.016)
					(thickness 0.1524)
				)
			)
		)
		(property "Device Type" "C603H36"
			(at 0 -4.3434 180)
			(unlocked yes)
			(layer "F.Fab")
			(hide yes)
			(effects
				(font
					(size 1.016 1.016)
					(thickness 0.1524)
				)
			)
		)
		(duplicate_pad_numbers_are_jumpers no)
		(fp_line
			(start 0.508 0)
			(end -0.508 0)
			(stroke
				(width 0.2032)
				(type default)
			)
			(layer "F.SilkS")
		)
		(fp_rect
			(start -0.5842 1.3335)
			(end 0.5842 -1.3335)
			(stroke
				(width 0)
				(type default)
			)
			(fill no)
			(layer "F.CrtYd")
		)
		(fp_rect
			(start -0.5842 1.3335)
			(end 0.5842 -1.3335)
			(stroke
				(width 0)
				(type default)
			)
			(fill no)
			(layer "F.Fab")
		)
		(pad "1" smd custom
			(at 0 -0.762 180)
			(size 0.2159 0.2159)
			(layers "F.Cu" "F.Mask" "F.Paste")
			(net "P12V_HDD27")
			(options
				(clearance outline)
				(anchor circle)
			)
			(primitives
				(gr_poly
					(pts
						(arc
							(start -0.3302 -0.4318)
							(mid -0.402042 -0.402042)
							(end -0.4318 -0.3302)
						)
						(arc
							(start -0.4318 0.3302)
							(mid -0.402042 0.402042)
							(end -0.3302 0.4318)
						)
						(arc
							(start 0.3302 0.4318)
							(mid 0.402042 0.402042)
							(end 0.4318 0.3302)
						)
						(arc
							(start 0.4318 -0.3302)
							(mid 0.402042 -0.402042)
							(end 0.3302 -0.4318)
						)
					)
					(width 0)
					(fill yes)
				)
			)
		)
		(pad "2" smd custom
			(at 0 0.762 180)
			(size 0.2159 0.2159)
			(layers "F.Cu" "F.Mask" "F.Paste")
			(net "GND")
			(options
				(clearance outline)
				(anchor circle)
			)
			(primitives
				(gr_poly
					(pts
						(arc
							(start -0.3302 -0.4318)
							(mid -0.402042 -0.402042)
							(end -0.4318 -0.3302)
						)
						(arc
							(start -0.4318 0.3302)
							(mid -0.402042 0.402042)
							(end -0.3302 0.4318)
						)
						(arc
							(start 0.3302 0.4318)
							(mid 0.402042 0.402042)
							(end 0.4318 0.3302)
						)
						(arc
							(start 0.4318 -0.3302)
							(mid 0.402042 -0.402042)
							(end 0.3302 -0.4318)
						)
					)
					(width 0)
					(fill yes)
				)
			)
		)
	)
	(footprint ""
		(layer "F.Cu")
		(at 392.938 -45.339 180)
		(property "Reference" "C452"
			(at 0 0 180)
			(layer "F.SilkS")
			(hide yes)
			(effects
				(font
					(size 1.27 1.27)
				)
			)
		)
		(property "Value" "SC1U25V3KX-GP"
			(at 0 -2.8194 180)
			(unlocked yes)
			(layer "F.Fab")
			(hide yes)
			(effects
				(font
					(size 1.016 1.016)
					(thickness 0.1524)
				)
			)
		)
		(property "Device Type" "C603H36"
			(at 0 -4.3434 180)
			(unlocked yes)
			(layer "F.Fab")
			(hide yes)
			(effects
				(font
					(size 1.016 1.016)
					(thickness 0.1524)
				)
			)
		)
		(duplicate_pad_numbers_are_jumpers no)
		(fp_line
			(start 0.508 0)
			(end -0.508 0)
			(stroke
				(width 0.2032)
				(type default)
			)
			(layer "F.SilkS")
		)
		(fp_rect
			(start -0.5842 1.3335)
			(end 0.5842 -1.3335)
			(stroke
				(width 0)
				(type default)
			)
			(fill no)
			(layer "F.CrtYd")
		)
		(fp_rect
			(start -0.5842 1.3335)
			(end 0.5842 -1.3335)
			(stroke
				(width 0)
				(type default)
			)
			(fill no)
			(layer "F.Fab")
		)
		(pad "1" smd custom
			(at 0 -0.762 180)
			(size 0.2159 0.2159)
			(layers "F.Cu" "F.Mask" "F.Paste")
			(net "P12V_HDD32")
			(options
				(clearance outline)
				(anchor circle)
			)
			(primitives
				(gr_poly
					(pts
						(arc
							(start -0.3302 -0.4318)
							(mid -0.402042 -0.402042)
							(end -0.4318 -0.3302)
						)
						(arc
							(start -0.4318 0.3302)
							(mid -0.402042 0.402042)
							(end -0.3302 0.4318)
						)
						(arc
							(start 0.3302 0.4318)
							(mid 0.402042 0.402042)
							(end 0.4318 0.3302)
						)
						(arc
							(start 0.4318 -0.3302)
							(mid 0.402042 -0.402042)
							(end 0.3302 -0.4318)
						)
					)
					(width 0)
					(fill yes)
				)
			)
		)
		(pad "2" smd custom
			(at 0 0.762 180)
			(size 0.2159 0.2159)
			(layers "F.Cu" "F.Mask" "F.Paste")
			(net "GND")
			(options
				(clearance outline)
				(anchor circle)
			)
			(primitives
				(gr_poly
					(pts
						(arc
							(start -0.3302 -0.4318)
							(mid -0.402042 -0.402042)
							(end -0.4318 -0.3302)
						)
						(arc
							(start -0.4318 0.3302)
							(mid -0.402042 0.402042)
							(end -0.3302 0.4318)
						)
						(arc
							(start 0.3302 0.4318)
							(mid 0.402042 0.402042)
							(end 0.4318 0.3302)
						)
						(arc
							(start 0.4318 -0.3302)
							(mid 0.402042 -0.402042)
							(end 0.3302 -0.4318)
						)
					)
					(width 0)
					(fill yes)
				)
			)
		)
	)
)
